(kicad_pcb
	(version 20221018)
	(generator pcbnew)
	(general
    (thickness 1.6)
  )
	(paper "A4")
	(title_block
    (title "NUC Computer Cluster Power Breakout HW")
    (date "2023-10-18")
    (rev "1.4.3")
    (company "Antmicro Ltd.")
		(comment 9 "footprints 133-145 of 234")
	)
	(layers
    (0 "F.Cu" mixed)
    (1 "In1.Cu" power)
    (2 "In2.Cu" mixed)
    (31 "B.Cu" power)
    (32 "B.Adhes" user "B.Adhesive")
    (33 "F.Adhes" user "F.Adhesive")
    (34 "B.Paste" user)
    (35 "F.Paste" user)
    (36 "B.SilkS" user "B.Silkscreen")
    (37 "F.SilkS" user "F.Silkscreen")
    (38 "B.Mask" user)
    (39 "F.Mask" user)
    (40 "Dwgs.User" user "User.Drawings")
    (41 "Cmts.User" user "User.Comments")
    (42 "Eco1.User" user "User.Eco1")
    (43 "Eco2.User" user "User.Eco2")
    (44 "Edge.Cuts" user)
    (45 "Margin" user)
    (46 "B.CrtYd" user "B.Courtyard")
    (47 "F.CrtYd" user "F.Courtyard")
    (48 "B.Fab" user)
    (49 "F.Fab" user)
  )
	(footprint "antmicro-footprints:R_0402_1005Metric" (layer "F.Cu")
    (at 169.9 115.1 180)
    (descr "Resistor SMD 0402")
    (tags "resistor SMD 0402")
    (property "Author" "Antmicro")
    (property "License" "Apache-2.0")
    (property "MPN" "CR0402-FX-1001GLF")
    (property "Manufacturer" "Bourns")
    (property "Sheetfile" "ftdi-module.kicad_sch")
    (property "Sheetname" "FTDI")
    (property "Tolerance" "1%")
    (property "Val" "1k")
    (property "ki_description" "SMD Chip Resistor, 1 kohm, ± 1%, 63 mW, 0402 [1005 Metric], Thick Film, General Purpose")
    (property "ki_keywords" "0402, SMT, RESISTOR, PASSIVE")
    (attr smd)
    (fp_text reference "R1" (at 0.75 0.45 180) (layer "F.SilkS")
        (effects (font (size 0.7 0.7) (thickness 0.15)) (justify left bottom))
    )
    (fp_text value "R_1k_0402" (at -1.011843 1.772047 180) (layer "F.Fab")
        (effects (font (size 0.7 0.7) (thickness 0.15)) (justify left bottom))
    )
    (fp_text user "${REFERENCE}" (at -0.95 3.168 180) (layer "F.Fab") hide
        (effects (font (size 0.7 0.7) (thickness 0.15)) (justify left bottom))
    )
    (fp_text user "Author: Antmicro" (at -0.95 4.169 180) (layer "F.Fab") hide
        (effects (font (size 0.7 0.7) (thickness 0.15)) (justify left bottom))
    )
    (fp_text user "License: Apache-2.0" (at -0.95 5.169 180) (layer "F.Fab") hide
        (effects (font (size 0.7 0.7) (thickness 0.15)) (justify left bottom))
    )
    (fp_rect (start -0.925 -0.47) (end 0.925 0.47)
      (stroke (width 0.05) (type default)) (fill none) (layer "F.CrtYd"))
    (fp_rect (start -0.5 -0.25) (end 0.5 0.25)
      (stroke (width 0.15) (type solid)) (fill none) (layer "F.Fab"))
    (pad "1" smd roundrect (at -0.48 0 180) (size 0.59 0.64) (layers "F.Cu" "F.Paste" "F.Mask") (roundrect_rratio 0.25)
      (net 76 "VCC3V3_USB") (pintype "passive"))
    (pad "2" smd roundrect (at 0.48 0 180) (size 0.59 0.64) (layers "F.Cu" "F.Paste" "F.Mask") (roundrect_rratio 0.25)
      (net 31 "/FTDI/FTDI_RST") (pintype "passive"))
  )
	(footprint "antmicro-footprints:R_0402_1005Metric" (layer "F.Cu")
    (at 96.4 137 90)
    (descr "Resistor SMD 0402")
    (tags "resistor SMD 0402")
    (property "Author" "Antmicro")
    (property "Current" "1A")
    (property "DNP" "DNP")
    (property "License" "Apache-2.0")
    (property "MPN" "ERJ2GE0R00X")
    (property "Manufacturer" "Panasonic")
    (property "Sheetfile" "d1600e-psu-breakout-board.kicad_sch")
    (property "Sheetname" "")
    (property "Tolerance" "")
    (property "Val" "0R")
    (property "dnp" "")
    (property "exclude_from_bom" "")
    (property "ki_description" "SMD Chip Resistor, Jumper, 0 ohm, 100 mW, 0402 [1005 Metric], Thick Film, General Purpose")
    (property "ki_keywords" "0402, SMT, RESISTOR, PASSIVE")
    (attr smd exclude_from_bom)
    (fp_text reference "R45" (at -3.2 0.45 90) (layer "F.SilkS")
        (effects (font (size 0.7 0.7) (thickness 0.15)) (justify left bottom))
    )
    (fp_text value "R_0R_0402" (at -1.011843 1.772047 90) (layer "F.Fab")
        (effects (font (size 0.7 0.7) (thickness 0.15)) (justify left bottom))
    )
    (fp_text user "Author: Antmicro" (at -0.95 4.169 90) (layer "F.Fab") hide
        (effects (font (size 0.7 0.7) (thickness 0.15)) (justify left bottom))
    )
    (fp_text user "License: Apache-2.0" (at -0.95 5.169 90) (layer "F.Fab") hide
        (effects (font (size 0.7 0.7) (thickness 0.15)) (justify left bottom))
    )
    (fp_text user "${REFERENCE}" (at -0.95 3.168 90) (layer "F.Fab") hide
        (effects (font (size 0.7 0.7) (thickness 0.15)) (justify left bottom))
    )
    (fp_rect (start -0.925 -0.47) (end 0.925 0.47)
      (stroke (width 0.05) (type default)) (fill none) (layer "F.CrtYd"))
    (fp_rect (start -0.5 -0.25) (end 0.5 0.25)
      (stroke (width 0.15) (type solid)) (fill none) (layer "F.Fab"))
    (pad "1" smd roundrect (at -0.48 0 90) (size 0.59 0.64) (layers "F.Cu" "F.Paste" "F.Mask") (roundrect_rratio 0.25)
      (net 4 "GND") (pintype "passive"))
    (pad "2" smd roundrect (at 0.48 0 90) (size 0.59 0.64) (layers "F.Cu" "F.Paste" "F.Mask") (roundrect_rratio 0.25)
      (net 51 "PSU_ON") (pintype "passive"))
  )
	(footprint "antmicro-footprints:TP_SMD_1mm" (layer "F.Cu")
    (at 123.4 137.4 -90)
    (property "Author" "Antmicro")
    (property "License" "Apache-2.0")
    (property "MPN" "")
    (property "Manufacturer" "")
    (property "Sheetfile" "d1600e-psu-breakout-board.kicad_sch")
    (property "Sheetname" "")
    (property "exclude_from_bom" "")
    (property "ki_description" "Test point 1mm SMD")
    (property "ki_keywords" "TESTPOINT")
    (attr exclude_from_pos_files exclude_from_bom)
    (fp_text reference "TP_S1" (at -0.8 -0.499996 -90) (layer "F.SilkS")
        (effects (font (size 0.7 0.7) (thickness 0.15)) (justify left bottom))
    )
    (fp_text value "TP_1mm_SMD" (at 0 1.4 -90) (layer "F.Fab")
        (effects (font (size 0.7 0.7) (thickness 0.15)) (justify left bottom))
    )
    (fp_text user "${REFERENCE}" (at -0.5 2.8 -90) (layer "F.Fab") hide
        (effects (font (size 0.7 0.7) (thickness 0.15)) (justify left bottom))
    )
    (fp_text user "Author: Antmicro" (at -0.5 4 -90) (layer "F.Fab") hide
        (effects (font (size 0.7 0.7) (thickness 0.15)) (justify left bottom))
    )
    (fp_text user "License: Apache-2.0" (at -0.5 5.2 -90) (layer "F.Fab") hide
        (effects (font (size 0.7 0.7) (thickness 0.15)) (justify left bottom))
    )
    (fp_circle (center 0 0) (end 0.6 0)
      (stroke (width 0.05) (type default)) (fill none) (layer "F.CrtYd"))
    (pad "1" smd circle (at 0 0 270) (size 1 1) (layers "F.Cu" "F.Mask")
      (net 64 "Net-(J10-PadS1)") (pinfunction "1") (pintype "passive"))
  )
	(footprint "antmicro-footprints:TP_SMD_1mm" (layer "F.Cu")
    (at 120.85 137.4 -90)
    (property "Author" "Antmicro")
    (property "License" "Apache-2.0")
    (property "MPN" "")
    (property "Manufacturer" "")
    (property "Sheetfile" "d1600e-psu-breakout-board.kicad_sch")
    (property "Sheetname" "")
    (property "exclude_from_bom" "")
    (property "ki_description" "Test point 1mm SMD")
    (property "ki_keywords" "TESTPOINT")
    (attr exclude_from_pos_files exclude_from_bom)
    (fp_text reference "TP_S3" (at -0.745801 -0.401591 -90) (layer "F.SilkS")
        (effects (font (size 0.7 0.7) (thickness 0.15)) (justify left bottom))
    )
    (fp_text value "TP_1mm_SMD" (at 0 1.4 -90) (layer "F.Fab")
        (effects (font (size 0.7 0.7) (thickness 0.15)) (justify left bottom))
    )
    (fp_text user "Author: Antmicro" (at -0.5 4 -90) (layer "F.Fab") hide
        (effects (font (size 0.7 0.7) (thickness 0.15)) (justify left bottom))
    )
    (fp_text user "License: Apache-2.0" (at -0.5 5.2 -90) (layer "F.Fab") hide
        (effects (font (size 0.7 0.7) (thickness 0.15)) (justify left bottom))
    )
    (fp_text user "${REFERENCE}" (at -0.5 2.8 -90) (layer "F.Fab") hide
        (effects (font (size 0.7 0.7) (thickness 0.15)) (justify left bottom))
    )
    (fp_circle (center 0 0) (end 0.6 0)
      (stroke (width 0.05) (type default)) (fill none) (layer "F.CrtYd"))
    (pad "1" smd circle (at 0 0 270) (size 1 1) (layers "F.Cu" "F.Mask")
      (net 66 "Net-(J10-PadS3)") (pinfunction "1") (pintype "passive"))
  )
	(footprint "antmicro-footprints:TP_SMD_1mm" (layer "F.Cu")
    (at 122.1 137.4 -90)
    (property "Author" "Antmicro")
    (property "License" "Apache-2.0")
    (property "MPN" "")
    (property "Manufacturer" "")
    (property "Sheetfile" "d1600e-psu-breakout-board.kicad_sch")
    (property "Sheetname" "")
    (property "exclude_from_bom" "")
    (property "ki_description" "Test point 1mm SMD")
    (property "ki_keywords" "TESTPOINT")
    (attr exclude_from_pos_files exclude_from_bom)
    (fp_text reference "TP_S2" (at -0.745801 -0.466104 -90) (layer "F.SilkS")
        (effects (font (size 0.7 0.7) (thickness 0.15)) (justify left bottom))
    )
    (fp_text value "TP_1mm_SMD" (at 0 1.4 -90) (layer "F.Fab")
        (effects (font (size 0.7 0.7) (thickness 0.15)) (justify left bottom))
    )
    (fp_text user "License: Apache-2.0" (at -0.5 5.2 -90) (layer "F.Fab") hide
        (effects (font (size 0.7 0.7) (thickness 0.15)) (justify left bottom))
    )
    (fp_text user "Author: Antmicro" (at -0.5 4 -90) (layer "F.Fab") hide
        (effects (font (size 0.7 0.7) (thickness 0.15)) (justify left bottom))
    )
    (fp_text user "${REFERENCE}" (at -0.5 2.8 -90) (layer "F.Fab") hide
        (effects (font (size 0.7 0.7) (thickness 0.15)) (justify left bottom))
    )
    (fp_circle (center 0 0) (end 0.6 0)
      (stroke (width 0.05) (type default)) (fill none) (layer "F.CrtYd"))
    (pad "1" smd circle (at 0 0 270) (size 1 1) (layers "F.Cu" "F.Mask")
      (net 65 "Net-(J10-PadS2)") (pinfunction "1") (pintype "passive"))
  )
	(footprint "antmicro-footprints:TP_SMD_1mm" (layer "F.Cu")
    (at 119.6 137.4 -90)
    (property "Author" "Antmicro")
    (property "License" "Apache-2.0")
    (property "MPN" "")
    (property "Manufacturer" "")
    (property "Sheetfile" "d1600e-psu-breakout-board.kicad_sch")
    (property "Sheetname" "")
    (property "exclude_from_bom" "")
    (property "ki_description" "Test point 1mm SMD")
    (property "ki_keywords" "TESTPOINT")
    (attr exclude_from_pos_files exclude_from_bom)
    (fp_text reference "TP_S4" (at -0.745801 -0.337078 -90) (layer "F.SilkS")
        (effects (font (size 0.7 0.7) (thickness 0.15)) (justify left bottom))
    )
    (fp_text value "TP_1mm_SMD" (at 0 1.4 -90) (layer "F.Fab")
        (effects (font (size 0.7 0.7) (thickness 0.15)) (justify left bottom))
    )
    (fp_text user "Author: Antmicro" (at -0.5 4 -90) (layer "F.Fab") hide
        (effects (font (size 0.7 0.7) (thickness 0.15)) (justify left bottom))
    )
    (fp_text user "${REFERENCE}" (at -0.5 2.8 -90) (layer "F.Fab") hide
        (effects (font (size 0.7 0.7) (thickness 0.15)) (justify left bottom))
    )
    (fp_text user "License: Apache-2.0" (at -0.5 5.2 -90) (layer "F.Fab") hide
        (effects (font (size 0.7 0.7) (thickness 0.15)) (justify left bottom))
    )
    (fp_circle (center 0 0) (end 0.6 0)
      (stroke (width 0.05) (type default)) (fill none) (layer "F.CrtYd"))
    (pad "1" smd circle (at 0 0 270) (size 1 1) (layers "F.Cu" "F.Mask")
      (net 67 "Net-(J10-PadS4)") (pinfunction "1") (pintype "passive"))
  )
	(footprint "antmicro-footprints:TP_SMD_1mm" (layer "F.Cu")
    (at 114.4 137.4 -90)
    (property "Author" "Antmicro")
    (property "License" "Apache-2.0")
    (property "MPN" "")
    (property "Manufacturer" "")
    (property "Sheetfile" "d1600e-psu-breakout-board.kicad_sch")
    (property "Sheetname" "")
    (property "exclude_from_bom" "")
    (property "ki_description" "Test point 1mm SMD")
    (property "ki_keywords" "TESTPOINT")
    (attr exclude_from_pos_files exclude_from_bom)
    (fp_text reference "TP_S8" (at -0.745801 -0.35 -90) (layer "F.SilkS")
        (effects (font (size 0.7 0.7) (thickness 0.15)) (justify left bottom))
    )
    (fp_text value "TP_1mm_SMD" (at 0 1.4 -90) (layer "F.Fab")
        (effects (font (size 0.7 0.7) (thickness 0.15)) (justify left bottom))
    )
    (fp_text user "Author: Antmicro" (at -0.5 4 -90) (layer "F.Fab") hide
        (effects (font (size 0.7 0.7) (thickness 0.15)) (justify left bottom))
    )
    (fp_text user "License: Apache-2.0" (at -0.5 5.2 -90) (layer "F.Fab") hide
        (effects (font (size 0.7 0.7) (thickness 0.15)) (justify left bottom))
    )
    (fp_text user "${REFERENCE}" (at -0.5 2.8 -90) (layer "F.Fab") hide
        (effects (font (size 0.7 0.7) (thickness 0.15)) (justify left bottom))
    )
    (fp_circle (center 0 0) (end 0.6 0)
      (stroke (width 0.05) (type default)) (fill none) (layer "F.CrtYd"))
    (pad "1" smd circle (at 0 0 270) (size 1 1) (layers "F.Cu" "F.Mask")
      (net 63 "Net-(J10-PadS8)") (pinfunction "1") (pintype "passive"))
  )
	(footprint "antmicro-footprints:TP_SMD_1mm" (layer "F.Cu")
    (at 115.625 137.425 -90)
    (property "Author" "Antmicro")
    (property "License" "Apache-2.0")
    (property "MPN" "")
    (property "Manufacturer" "")
    (property "Sheetfile" "d1600e-psu-breakout-board.kicad_sch")
    (property "Sheetname" "")
    (property "exclude_from_bom" "")
    (property "ki_description" "Test point 1mm SMD")
    (property "ki_keywords" "TESTPOINT")
    (attr exclude_from_pos_files exclude_from_bom)
    (fp_text reference "TP_S7" (at -0.725 -0.525 -90) (layer "F.SilkS")
        (effects (font (size 0.7 0.7) (thickness 0.15)) (justify left bottom))
    )
    (fp_text value "TP_1mm_SMD" (at 0 1.4 -90) (layer "F.Fab")
        (effects (font (size 0.7 0.7) (thickness 0.15)) (justify left bottom))
    )
    (fp_text user "Author: Antmicro" (at -0.5 4 -90) (layer "F.Fab") hide
        (effects (font (size 0.7 0.7) (thickness 0.15)) (justify left bottom))
    )
    (fp_text user "${REFERENCE}" (at -0.5 2.8 -90) (layer "F.Fab") hide
        (effects (font (size 0.7 0.7) (thickness 0.15)) (justify left bottom))
    )
    (fp_text user "License: Apache-2.0" (at -0.5 5.2 -90) (layer "F.Fab") hide
        (effects (font (size 0.7 0.7) (thickness 0.15)) (justify left bottom))
    )
    (fp_circle (center 0 0) (end 0.6 0)
      (stroke (width 0.05) (type default)) (fill none) (layer "F.CrtYd"))
    (pad "1" smd circle (at 0 0 270) (size 1 1) (layers "F.Cu" "F.Mask")
      (net 62 "Net-(J10-PadS7)") (pinfunction "1") (pintype "passive"))
  )
	(footprint "antmicro-footprints:TP_SMD_1mm" (layer "F.Cu")
    (at 118.3 137.4 -90)
    (property "Author" "Antmicro")
    (property "License" "Apache-2.0")
    (property "MPN" "")
    (property "Manufacturer" "")
    (property "Sheetfile" "d1600e-psu-breakout-board.kicad_sch")
    (property "Sheetname" "")
    (property "exclude_from_bom" "")
    (property "ki_description" "Test point 1mm SMD")
    (property "ki_keywords" "TESTPOINT")
    (attr exclude_from_pos_files exclude_from_bom)
    (fp_text reference "TP_S5" (at -0.745801 -0.322565 -90) (layer "F.SilkS")
        (effects (font (size 0.7 0.7) (thickness 0.15)) (justify left bottom))
    )
    (fp_text value "TP_1mm_SMD" (at 0 1.4 -90) (layer "F.Fab")
        (effects (font (size 0.7 0.7) (thickness 0.15)) (justify left bottom))
    )
    (fp_text user "Author: Antmicro" (at -0.5 4 -90) (layer "F.Fab") hide
        (effects (font (size 0.7 0.7) (thickness 0.15)) (justify left bottom))
    )
    (fp_text user "License: Apache-2.0" (at -0.5 5.2 -90) (layer "F.Fab") hide
        (effects (font (size 0.7 0.7) (thickness 0.15)) (justify left bottom))
    )
    (fp_text user "${REFERENCE}" (at -0.5 2.8 -90) (layer "F.Fab") hide
        (effects (font (size 0.7 0.7) (thickness 0.15)) (justify left bottom))
    )
    (fp_circle (center 0 0) (end 0.6 0)
      (stroke (width 0.05) (type default)) (fill none) (layer "F.CrtYd"))
    (pad "1" smd circle (at 0 0 270) (size 1 1) (layers "F.Cu" "F.Mask")
      (net 60 "Net-(J10-PadS5)") (pinfunction "1") (pintype "passive"))
  )
	(footprint "antmicro-footprints:TP_SMD_1mm" (layer "F.Cu")
    (at 117 137.4 -90)
    (property "Author" "Antmicro")
    (property "License" "Apache-2.0")
    (property "MPN" "")
    (property "Manufacturer" "")
    (property "Sheetfile" "d1600e-psu-breakout-board.kicad_sch")
    (property "Sheetname" "")
    (property "exclude_from_bom" "")
    (property "ki_description" "Test point 1mm SMD")
    (property "ki_keywords" "TESTPOINT")
    (attr exclude_from_pos_files exclude_from_bom)
    (fp_text reference "TP_S6" (at -0.745801 -0.308052 -90) (layer "F.SilkS")
        (effects (font (size 0.7 0.7) (thickness 0.15)) (justify left bottom))
    )
    (fp_text value "TP_1mm_SMD" (at 0 1.4 -90) (layer "F.Fab")
        (effects (font (size 0.7 0.7) (thickness 0.15)) (justify left bottom))
    )
    (fp_text user "${REFERENCE}" (at -0.5 2.8 -90) (layer "F.Fab") hide
        (effects (font (size 0.7 0.7) (thickness 0.15)) (justify left bottom))
    )
    (fp_text user "License: Apache-2.0" (at -0.5 5.2 -90) (layer "F.Fab") hide
        (effects (font (size 0.7 0.7) (thickness 0.15)) (justify left bottom))
    )
    (fp_text user "Author: Antmicro" (at -0.5 4 -90) (layer "F.Fab") hide
        (effects (font (size 0.7 0.7) (thickness 0.15)) (justify left bottom))
    )
    (fp_circle (center 0 0) (end 0.6 0)
      (stroke (width 0.05) (type default)) (fill none) (layer "F.CrtYd"))
    (pad "1" smd circle (at 0 0 270) (size 1 1) (layers "F.Cu" "F.Mask")
      (net 61 "Net-(J10-PadS6)") (pinfunction "1") (pintype "passive"))
  )
	(footprint "antmicro-footprints:TP_SMD_1mm" (layer "F.Cu")
    (at 107 136.5508)
    (property "Author" "Antmicro")
    (property "License" "Apache-2.0")
    (property "MPN" "")
    (property "Manufacturer" "")
    (property "Sheetfile" "d1600e-psu-breakout-board.kicad_sch")
    (property "Sheetname" "")
    (property "exclude_from_bom" "")
    (property "ki_description" "Test point 1mm SMD")
    (property "ki_keywords" "TESTPOINT")
    (attr exclude_from_pos_files exclude_from_bom)
    (fp_text reference "TP_S_ON1" (at 0.3 -0.4508 90) (layer "F.SilkS")
        (effects (font (size 0.7 0.7) (thickness 0.15)) (justify left bottom))
    )
    (fp_text value "TP_1mm_SMD" (at 0 1.4) (layer "F.Fab")
        (effects (font (size 0.7 0.7) (thickness 0.15)) (justify left bottom))
    )
    (fp_text user "Author: Antmicro" (at -0.5 4) (layer "F.Fab") hide
        (effects (font (size 0.7 0.7) (thickness 0.15)) (justify left bottom))
    )
    (fp_text user "License: Apache-2.0" (at -0.5 5.2) (layer "F.Fab") hide
        (effects (font (size 0.7 0.7) (thickness 0.15)) (justify left bottom))
    )
    (fp_text user "${REFERENCE}" (at -0.5 2.8) (layer "F.Fab") hide
        (effects (font (size 0.7 0.7) (thickness 0.15)) (justify left bottom))
    )
    (fp_circle (center 0 0) (end 0.6 0)
      (stroke (width 0.05) (type default)) (fill none) (layer "F.CrtYd"))
    (pad "1" smd circle (at 0 0) (size 1 1) (layers "F.Cu" "F.Mask")
      (net 51 "PSU_ON") (pinfunction "1") (pintype "passive"))
  )
	(footprint "antmicro-footprints:TP_SMD_1mm" (layer "F.Cu")
    (at 172.45 115.1)
    (property "Author" "Antmicro")
    (property "License" "Apache-2.0")
    (property "MPN" "")
    (property "Manufacturer" "")
    (property "Sheetfile" "ftdi-module.kicad_sch")
    (property "Sheetname" "FTDI")
    (property "exclude_from_bom" "")
    (property "ki_description" "Test point 1mm SMD")
    (property "ki_keywords" "TESTPOINT")
    (attr exclude_from_pos_files exclude_from_bom)
    (fp_text reference "SCL_FTDI1" (at 0.55 0.1) (layer "F.SilkS")
        (effects (font (size 0.7 0.7) (thickness 0.15)) (justify left bottom))
    )
    (fp_text value "TP_1mm_SMD" (at 0 1.4) (layer "F.Fab")
        (effects (font (size 0.7 0.7) (thickness 0.15)) (justify left bottom))
    )
    (fp_text user "License: Apache-2.0" (at -0.5 5.2) (layer "F.Fab") hide
        (effects (font (size 0.7 0.7) (thickness 0.15)) (justify left bottom))
    )
    (fp_text user "${REFERENCE}" (at -0.5 2.8) (layer "F.Fab") hide
        (effects (font (size 0.7 0.7) (thickness 0.15)) (justify left bottom))
    )
    (fp_text user "Author: Antmicro" (at -0.5 4) (layer "F.Fab") hide
        (effects (font (size 0.7 0.7) (thickness 0.15)) (justify left bottom))
    )
    (fp_circle (center 0 0) (end 0.6 0)
      (stroke (width 0.05) (type default)) (fill none) (layer "F.CrtYd"))
    (pad "1" smd circle (at 0 0) (size 1 1) (layers "F.Cu" "F.Mask")
      (net 81 "SCL_FTDI") (pinfunction "1") (pintype "passive"))
  )
	(footprint "antmicro-footprints:TP_SMD_1mm" (layer "F.Cu")
    (at 172.05 112.6)
    (property "Author" "Antmicro")
    (property "License" "Apache-2.0")
    (property "MPN" "")
    (property "Manufacturer" "")
    (property "Sheetfile" "ftdi-module.kicad_sch")
    (property "Sheetname" "FTDI")
    (property "exclude_from_bom" "")
    (property "ki_description" "Test point 1mm SMD")
    (property "ki_keywords" "TESTPOINT")
    (attr exclude_from_pos_files exclude_from_bom)
    (fp_text reference "SDA_FTDI1" (at 0.2 1.45) (layer "F.SilkS")
        (effects (font (size 0.7 0.7) (thickness 0.15)) (justify left bottom))
    )
    (fp_text value "TP_1mm_SMD" (at 0 1.4) (layer "F.Fab")
        (effects (font (size 0.7 0.7) (thickness 0.15)) (justify left bottom))
    )
    (fp_text user "License: Apache-2.0" (at -0.5 5.2) (layer "F.Fab") hide
        (effects (font (size 0.7 0.7) (thickness 0.15)) (justify left bottom))
    )
    (fp_text user "${REFERENCE}" (at -0.5 2.8) (layer "F.Fab") hide
        (effects (font (size 0.7 0.7) (thickness 0.15)) (justify left bottom))
    )
    (fp_text user "Author: Antmicro" (at -0.5 4) (layer "F.Fab") hide
        (effects (font (size 0.7 0.7) (thickness 0.15)) (justify left bottom))
    )
    (fp_circle (center 0 0) (end 0.6 0)
      (stroke (width 0.05) (type default)) (fill none) (layer "F.CrtYd"))
    (pad "1" smd circle (at 0 0) (size 1 1) (layers "F.Cu" "F.Mask")
      (net 80 "SDA_FTDI") (pinfunction "1") (pintype "passive"))
  )
)
